(kicad_pcb
	(version 20260206)
	(generator "pcbnew")
	(generator_version "10.0")
	(general
		(thickness 1.6)
		(legacy_teardrops no)
	)
	(paper "A4")
	(title_block
		(title "04192023_DAF0TMB3IC0_F0TG_MB_C_brd_V02_OCP.brd")
		(comment 1 "Grand Teton / footprints 2681-2685 of 8354")
	)
	(layers
		(0 "F.Cu" signal "TOP")
		(4 "In1.Cu" signal "GND")
		(6 "In2.Cu" signal "IN1")
		(8 "In3.Cu" signal "GND1")
		(10 "In4.Cu" signal "IN2")
		(12 "In5.Cu" signal "GND2")
		(14 "In6.Cu" signal "IN3")
		(16 "In7.Cu" signal "GND3")
		(18 "In8.Cu" signal "VCC")
		(20 "In9.Cu" signal "VCC1")
		(22 "In10.Cu" signal "GND4")
		(24 "In11.Cu" signal "IN4")
		(26 "In12.Cu" signal "GND5")
		(28 "In13.Cu" signal "IN5")
		(30 "In14.Cu" signal "GND6")
		(32 "In15.Cu" signal "IN6")
		(34 "In16.Cu" signal "GND7")
		(2 "B.Cu" signal "BOTTOM")
		(9 "F.Adhes" user "F.Adhesive")
		(11 "B.Adhes" user "B.Adhesive")
		(13 "F.Paste" user "Package Geometry/Pastemask Top")
		(15 "B.Paste" user "Package Geometry/Pastemask Bottom")
		(5 "F.SilkS" user "Ref Des/Silkscreen Top")
		(7 "B.SilkS" user "Ref Des/Silkscreen Bottom")
		(1 "F.Mask" user "Board Geometry/Soldermask Top")
		(3 "B.Mask" user "Board Geometry/Soldermask Bottom")
		(17 "Dwgs.User" user "User.Drawings")
		(19 "Cmts.User" user "User.Comments")
		(21 "Eco1.User" user "User.Eco1")
		(23 "Eco2.User" user "User.Eco2")
		(25 "Edge.Cuts" user "Board Geometry/Outline")
		(27 "Margin" user)
		(31 "F.CrtYd" user "Package Geometry/Place Bound Top")
		(29 "B.CrtYd" user "Package Geometry/Place Bound Bottom")
		(35 "F.Fab" user "Ref Des/Assembly Top")
		(33 "B.Fab" user "Ref Des/Assembly Bottom")
	)
	(footprint ""
		(layer "F.Cu")
		(at 450.508878 -399.340578 90)
		(property "Reference" "PC6575"
			(at 0 0 90)
			(layer "F.SilkS")
			(hide yes)
			(effects
				(font
					(size 1.27 1.27)
				)
			)
		)
		(property "Value" ""
			(at 0 0 90)
			(layer "F.Fab")
			(effects
				(font
					(size 1.27 1.27)
				)
			)
		)
		(duplicate_pad_numbers_are_jumpers no)
		(fp_line
			(start 0.7874 -0.4064)
			(end 0.7874 -0.192278)
			(stroke
				(width 0.1524)
				(type default)
			)
			(layer "F.SilkS")
		)
		(fp_line
			(start -0.7874 -0.4064)
			(end 0.7874 -0.4064)
			(stroke
				(width 0.1524)
				(type default)
			)
			(layer "F.SilkS")
		)
		(fp_line
			(start 0.455422 0.4064)
			(end -0.7874 0.4064)
			(stroke
				(width 0.1524)
				(type default)
			)
			(layer "F.SilkS")
		)
		(fp_line
			(start -0.7874 0.4064)
			(end -0.7874 -0.4064)
			(stroke
				(width 0.1524)
				(type default)
			)
			(layer "F.SilkS")
		)
		(fp_line
			(start -0.12065 -0.305054)
			(end -0.12065 -0.2794)
			(stroke
				(width 0.1)
				(type default)
			)
			(layer "F.Fab")
		)
		(fp_line
			(start -0.67945 -0.305054)
			(end -0.12065 -0.305054)
			(stroke
				(width 0.1)
				(type default)
			)
			(layer "F.Fab")
		)
		(fp_line
			(start 0.67945 -0.3048)
			(end 0.67945 0.3048)
			(stroke
				(width 0.1)
				(type default)
			)
			(layer "F.Fab")
		)
		(fp_line
			(start 0.12065 -0.3048)
			(end 0.67945 -0.3048)
			(stroke
				(width 0.1)
				(type default)
			)
			(layer "F.Fab")
		)
		(fp_line
			(start 0.12065 -0.2794)
			(end 0.12065 -0.3048)
			(stroke
				(width 0.1)
				(type default)
			)
			(layer "F.Fab")
		)
		(fp_line
			(start -0.12065 -0.2794)
			(end 0.12065 -0.2794)
			(stroke
				(width 0.1)
				(type default)
			)
			(layer "F.Fab")
		)
		(fp_line
			(start 0.120396 0.2794)
			(end -0.12065 0.2794)
			(stroke
				(width 0.1)
				(type default)
			)
			(layer "F.Fab")
		)
		(fp_line
			(start -0.12065 0.2794)
			(end -0.12065 0.3048)
			(stroke
				(width 0.1)
				(type default)
			)
			(layer "F.Fab")
		)
		(fp_line
			(start 0.67945 0.3048)
			(end 0.120396 0.3048)
			(stroke
				(width 0.1)
				(type default)
			)
			(layer "F.Fab")
		)
		(fp_line
			(start 0.120396 0.3048)
			(end 0.120396 0.2794)
			(stroke
				(width 0.1)
				(type default)
			)
			(layer "F.Fab")
		)
		(fp_line
			(start -0.12065 0.3048)
			(end -0.67945 0.3048)
			(stroke
				(width 0.1)
				(type default)
			)
			(layer "F.Fab")
		)
		(fp_line
			(start -0.67945 0.3048)
			(end -0.67945 -0.305054)
			(stroke
				(width 0.1)
				(type default)
			)
			(layer "F.Fab")
		)
		(pad "1" smd circle
			(at -0.40005 0 90)
			(size 0 0)
			(layers "F.Cu" "F.Mask" "F.Paste")
			(net "P0V9_RETIMER_CPU0_VCC2")
		)
		(pad "2" smd circle
			(at 0.40005 0 90)
			(size 0 0)
			(layers "F.Cu" "F.Mask" "F.Paste")
			(net "GND")
		)
	)
	(footprint ""
		(layer "F.Cu")
		(at 76.252324 -408.517344 -90)
		(property "Reference" "C6647"
			(at 0 0 270)
			(layer "F.SilkS")
			(hide yes)
			(effects
				(font
					(size 1.27 1.27)
				)
			)
		)
		(property "Value" ""
			(at 0 0 270)
			(layer "F.Fab")
			(effects
				(font
					(size 1.27 1.27)
				)
			)
		)
		(duplicate_pad_numbers_are_jumpers no)
		(fp_line
			(start -0.299974 0.150114)
			(end -0.299974 -0.150114)
			(stroke
				(width 0.1)
				(type default)
			)
			(layer "F.Fab")
		)
		(fp_line
			(start 0.299974 0.150114)
			(end -0.299974 0.150114)
			(stroke
				(width 0.1)
				(type default)
			)
			(layer "F.Fab")
		)
		(fp_line
			(start -0.299974 -0.150114)
			(end 0.299974 -0.150114)
			(stroke
				(width 0.1)
				(type default)
			)
			(layer "F.Fab")
		)
		(fp_line
			(start 0.299974 -0.150114)
			(end 0.299974 0.150114)
			(stroke
				(width 0.1)
				(type default)
			)
			(layer "F.Fab")
		)
		(pad "1" smd rect
			(at -0.2667 0 270)
			(size 0.3048 0.381)
			(layers "F.Cu" "F.Mask" "F.Paste")
			(net "P5E_CPU1_P0_TX_BUF_C_DP<9>")
		)
		(pad "2" smd rect
			(at 0.2667 0 270)
			(size 0.3048 0.381)
			(layers "F.Cu" "F.Mask" "F.Paste")
			(net "P5E_CPU1_P0_TX_BUF_DP<9>")
		)
	)
	(footprint ""
		(layer "F.Cu")
		(at 66.635122 -148.335746 180)
		(property "Reference" "PC19"
			(at 0 0 180)
			(layer "F.SilkS")
			(hide yes)
			(effects
				(font
					(size 1.27 1.27)
				)
			)
		)
		(property "Value" ""
			(at 0 0 180)
			(layer "F.Fab")
			(effects
				(font
					(size 1.27 1.27)
				)
			)
		)
		(duplicate_pad_numbers_are_jumpers no)
		(fp_line
			(start 0.7874 0.4064)
			(end -0.7874 0.4064)
			(stroke
				(width 0.1524)
				(type default)
			)
			(layer "F.SilkS")
		)
		(fp_line
			(start 0.7874 -0.4064)
			(end 0.7874 0.4064)
			(stroke
				(width 0.1524)
				(type default)
			)
			(layer "F.SilkS")
		)
		(fp_line
			(start -0.7874 0.4064)
			(end -0.7874 -0.4064)
			(stroke
				(width 0.1524)
				(type default)
			)
			(layer "F.SilkS")
		)
		(fp_line
			(start -0.7874 -0.4064)
			(end 0.7874 -0.4064)
			(stroke
				(width 0.1524)
				(type default)
			)
			(layer "F.SilkS")
		)
		(fp_line
			(start 0.67945 0.3048)
			(end 0.120396 0.3048)
			(stroke
				(width 0.1)
				(type default)
			)
			(layer "F.Fab")
		)
		(fp_line
			(start 0.67945 -0.3048)
			(end 0.67945 0.3048)
			(stroke
				(width 0.1)
				(type default)
			)
			(layer "F.Fab")
		)
		(fp_line
			(start 0.12065 -0.2794)
			(end 0.12065 -0.3048)
			(stroke
				(width 0.1)
				(type default)
			)
			(layer "F.Fab")
		)
		(fp_line
			(start 0.12065 -0.3048)
			(end 0.67945 -0.3048)
			(stroke
				(width 0.1)
				(type default)
			)
			(layer "F.Fab")
		)
		(fp_line
			(start 0.120396 0.3048)
			(end 0.120396 0.2794)
			(stroke
				(width 0.1)
				(type default)
			)
			(layer "F.Fab")
		)
		(fp_line
			(start 0.120396 0.2794)
			(end -0.12065 0.2794)
			(stroke
				(width 0.1)
				(type default)
			)
			(layer "F.Fab")
		)
		(fp_line
			(start -0.12065 0.3048)
			(end -0.67945 0.3048)
			(stroke
				(width 0.1)
				(type default)
			)
			(layer "F.Fab")
		)
		(fp_line
			(start -0.12065 0.2794)
			(end -0.12065 0.3048)
			(stroke
				(width 0.1)
				(type default)
			)
			(layer "F.Fab")
		)
		(fp_line
			(start -0.12065 -0.2794)
			(end 0.12065 -0.2794)
			(stroke
				(width 0.1)
				(type default)
			)
			(layer "F.Fab")
		)
		(fp_line
			(start -0.12065 -0.305054)
			(end -0.12065 -0.2794)
			(stroke
				(width 0.1)
				(type default)
			)
			(layer "F.Fab")
		)
		(fp_line
			(start -0.67945 0.3048)
			(end -0.67945 -0.305054)
			(stroke
				(width 0.1)
				(type default)
			)
			(layer "F.Fab")
		)
		(fp_line
			(start -0.67945 -0.305054)
			(end -0.12065 -0.305054)
			(stroke
				(width 0.1)
				(type default)
			)
			(layer "F.Fab")
		)
		(pad "1" smd circle
			(at -0.40005 0 180)
			(size 0 0)
			(layers "F.Cu" "F.Mask" "F.Paste")
			(net "SW_PVDD18_S5_P1_BST_R")
		)
		(pad "2" smd circle
			(at 0.40005 0 180)
			(size 0 0)
			(layers "F.Cu" "F.Mask" "F.Paste")
			(net "SW_PVDD18_S5_P1_SW")
		)
	)
	(footprint ""
		(layer "F.Cu")
		(at 251.16409 -49.137062 -90)
		(property "Reference" "PC2206"
			(at 0 0 270)
			(layer "F.SilkS")
			(hide yes)
			(effects
				(font
					(size 1.27 1.27)
				)
			)
		)
		(property "Value" ""
			(at 0 0 270)
			(layer "F.Fab")
			(effects
				(font
					(size 1.27 1.27)
				)
			)
		)
		(duplicate_pad_numbers_are_jumpers no)
		(fp_line
			(start -0.7874 0.4064)
			(end -0.7874 -0.4064)
			(stroke
				(width 0.1524)
				(type default)
			)
			(layer "F.SilkS")
		)
		(fp_line
			(start 0.7874 0.4064)
			(end -0.7874 0.4064)
			(stroke
				(width 0.1524)
				(type default)
			)
			(layer "F.SilkS")
		)
		(fp_line
			(start -0.7874 -0.4064)
			(end 0.7874 -0.4064)
			(stroke
				(width 0.1524)
				(type default)
			)
			(layer "F.SilkS")
		)
		(fp_line
			(start 0.7874 -0.4064)
			(end 0.7874 0.4064)
			(stroke
				(width 0.1524)
				(type default)
			)
			(layer "F.SilkS")
		)
		(fp_line
			(start -0.67945 0.3048)
			(end -0.67945 -0.305054)
			(stroke
				(width 0.1)
				(type default)
			)
			(layer "F.Fab")
		)
		(fp_line
			(start -0.12065 0.3048)
			(end -0.67945 0.3048)
			(stroke
				(width 0.1)
				(type default)
			)
			(layer "F.Fab")
		)
		(fp_line
			(start 0.120396 0.3048)
			(end 0.120396 0.2794)
			(stroke
				(width 0.1)
				(type default)
			)
			(layer "F.Fab")
		)
		(fp_line
			(start 0.67945 0.3048)
			(end 0.120396 0.3048)
			(stroke
				(width 0.1)
				(type default)
			)
			(layer "F.Fab")
		)
		(fp_line
			(start -0.12065 0.2794)
			(end -0.12065 0.3048)
			(stroke
				(width 0.1)
				(type default)
			)
			(layer "F.Fab")
		)
		(fp_line
			(start 0.120396 0.2794)
			(end -0.12065 0.2794)
			(stroke
				(width 0.1)
				(type default)
			)
			(layer "F.Fab")
		)
		(fp_line
			(start -0.12065 -0.2794)
			(end 0.12065 -0.2794)
			(stroke
				(width 0.1)
				(type default)
			)
			(layer "F.Fab")
		)
		(fp_line
			(start 0.12065 -0.2794)
			(end 0.12065 -0.3048)
			(stroke
				(width 0.1)
				(type default)
			)
			(layer "F.Fab")
		)
		(fp_line
			(start 0.12065 -0.3048)
			(end 0.67945 -0.3048)
			(stroke
				(width 0.1)
				(type default)
			)
			(layer "F.Fab")
		)
		(fp_line
			(start 0.67945 -0.3048)
			(end 0.67945 0.3048)
			(stroke
				(width 0.1)
				(type default)
			)
			(layer "F.Fab")
		)
		(fp_line
			(start -0.67945 -0.305054)
			(end -0.12065 -0.305054)
			(stroke
				(width 0.1)
				(type default)
			)
			(layer "F.Fab")
		)
		(fp_line
			(start -0.12065 -0.305054)
			(end -0.12065 -0.2794)
			(stroke
				(width 0.1)
				(type default)
			)
			(layer "F.Fab")
		)
		(pad "1" smd circle
			(at -0.40005 0 270)
			(size 0 0)
			(layers "F.Cu" "F.Mask" "F.Paste")
			(net "P12V_E1S_0")
		)
		(pad "2" smd circle
			(at 0.40005 0 270)
			(size 0 0)
			(layers "F.Cu" "F.Mask" "F.Paste")
			(net "GND")
		)
	)
	(footprint ""
		(layer "F.Cu")
		(at 231.540558 -401.920202 180)
		(property "Reference" "PU297"
			(at 2.622804 -5.10286 90)
			(unlocked yes)
			(layer "F.SilkS")
			(effects
				(font
					(size 0.7874 0.5842)
					(thickness 0.1524)
				)
			)
		)
		(property "Value" ""
			(at 0 0 180)
			(layer "F.Fab")
			(effects
				(font
					(size 1.27 1.27)
				)
			)
		)
		(duplicate_pad_numbers_are_jumpers no)
		(fp_line
			(start 2.567686 2.567686)
			(end 2.567686 -2.567686)
			(stroke
				(width 0.1524)
				(type default)
			)
			(layer "F.SilkS")
		)
		(fp_line
			(start 2.567686 -2.567686)
			(end -2.567686 -2.567686)
			(stroke
				(width 0.1524)
				(type default)
			)
			(layer "F.SilkS")
		)
		(fp_line
			(start -2.567686 2.567686)
			(end 2.567686 2.567686)
			(stroke
				(width 0.1524)
				(type default)
			)
			(layer "F.SilkS")
		)
		(fp_line
			(start -2.567686 -2.567686)
			(end -2.567686 2.567686)
			(stroke
				(width 0.1524)
				(type default)
			)
			(layer "F.SilkS")
		)
		(fp_poly
			(pts
				(xy -2.632456 -2.13233) (xy -3.709924 -2.491486) (xy -2.991612 -3.209798)
			)
			(stroke
				(width 0)
				(type default)
			)
			(fill yes)
			(layer "F.SilkS")
		)
		(fp_line
			(start 2.549906 2.549906)
			(end 2.549906 -2.549906)
			(stroke
				(width 0.1)
				(type default)
			)
			(layer "F.Fab")
		)
		(fp_line
			(start 2.549906 -2.549906)
			(end -2.549906 -2.549906)
			(stroke
				(width 0.1)
				(type default)
			)
			(layer "F.Fab")
		)
		(fp_line
			(start -2.549906 2.549906)
			(end 2.549906 2.549906)
			(stroke
				(width 0.1)
				(type default)
			)
			(layer "F.Fab")
		)
		(fp_line
			(start -2.549906 -2.549906)
			(end -2.549906 2.549906)
			(stroke
				(width 0.1)
				(type default)
			)
			(layer "F.Fab")
		)
		(fp_poly
			(pts
				(xy -3.806698 -2.25806) (xy -3.806698 -1.24206) (xy -2.790698 -1.75006)
			)
			(stroke
				(width 0)
				(type default)
			)
			(fill yes)
			(layer "F.Fab")
		)
		(pad "1" smd rect
			(at -2.250186 -1.75006 270)
			(size 0.254 0.3556)
			(layers "F.Cu" "F.Mask" "F.Paste")
			(net "P12V_AUX")
		)
		(pad "2" smd rect
			(at -2.237486 -1.249934 270)
			(size 0.254 0.381)
			(layers "F.Cu" "F.Mask" "F.Paste")
			(net "P12V_AUX")
		)
		(pad "3" smd rect
			(at -2.237486 -0.750062 270)
			(size 0.254 0.381)
			(layers "F.Cu" "F.Mask" "F.Paste")
			(net "HSC_D_OC_4")
		)
		(pad "4" smd rect
			(at -2.237486 -0.249936 270)
			(size 0.254 0.381)
			(layers "F.Cu" "F.Mask" "F.Paste")
			(net "HSC_ON")
		)
		(pad "5" smd rect
			(at -2.237486 0.249936 270)
			(size 0.254 0.381)
			(layers "F.Cu" "F.Mask" "F.Paste")
			(net "HSC_FAULT")
		)
		(pad "6" smd rect
			(at -2.237486 0.750062 270)
			(size 0.254 0.381)
			(layers "F.Cu" "F.Mask" "F.Paste")
			(net "HSC_FLT_TYPE_4")
		)
		(pad "7" smd rect
			(at -2.237486 1.249934 270)
			(size 0.254 0.381)
			(layers "F.Cu" "F.Mask" "F.Paste")
			(net "HSC_NC1_4")
		)
		(pad "8" smd rect
			(at -2.250186 1.75006 270)
			(size 0.254 0.3556)
			(layers "F.Cu" "F.Mask" "F.Paste")
			(net "HSC_MODE_4")
		)
		(pad "9" smd rect
			(at -1.75006 2.250186 180)
			(size 0.254 0.3556)
			(layers "F.Cu" "F.Mask" "F.Paste")
			(net "P12V_PSU")
		)
		(pad "10" smd rect
			(at -1.249934 2.237486 180)
			(size 0.254 0.381)
			(layers "F.Cu" "F.Mask" "F.Paste")
			(net "P12V_PSU")
		)
		(pad "11" smd rect
			(at -0.750062 2.237486 180)
			(size 0.254 0.381)
			(layers "F.Cu" "F.Mask" "F.Paste")
			(net "P12V_PSU")
		)
		(pad "12" smd rect
			(at -0.249936 2.237486 180)
			(size 0.254 0.381)
			(layers "F.Cu" "F.Mask" "F.Paste")
			(net "P12V_PSU")
		)
		(pad "13" smd rect
			(at 0.249936 2.237486 180)
			(size 0.254 0.381)
			(layers "F.Cu" "F.Mask" "F.Paste")
			(net "P12V_PSU")
		)
		(pad "14" smd rect
			(at 0.750062 2.237486 180)
			(size 0.254 0.381)
			(layers "F.Cu" "F.Mask" "F.Paste")
			(net "P12V_PSU")
		)
		(pad "15" smd rect
			(at 1.249934 2.237486 180)
			(size 0.254 0.381)
			(layers "F.Cu" "F.Mask" "F.Paste")
			(net "P12V_PSU")
		)
		(pad "16" smd rect
			(at 1.75006 2.250186 180)
			(size 0.254 0.3556)
			(layers "F.Cu" "F.Mask" "F.Paste")
			(net "P12V_PSU")
		)
		(pad "17" smd rect
			(at 2.250186 1.75006 270)
			(size 0.254 0.3556)
			(layers "F.Cu" "F.Mask" "F.Paste")
			(net "HSC_SCREF_4")
		)
		(pad "18" smd rect
			(at 2.237486 1.249934 270)
			(size 0.254 0.381)
			(layers "F.Cu" "F.Mask" "F.Paste")
			(net "HSC_VTEMP")
		)
		(pad "19" smd rect
			(at 2.237486 0.750062 270)
			(size 0.254 0.381)
			(layers "F.Cu" "F.Mask" "F.Paste")
			(net "HSC_SS")
		)
		(pad "20" smd rect
			(at 2.237486 0.249936 270)
			(size 0.254 0.381)
			(layers "F.Cu" "F.Mask" "F.Paste")
			(net "AGND_HSC")
		)
		(pad "21" smd rect
			(at 2.237486 -0.249936 270)
			(size 0.254 0.381)
			(layers "F.Cu" "F.Mask" "F.Paste")
			(net "HSC_VDD_R_4")
		)
		(pad "22" smd rect
			(at 2.237486 -0.750062 270)
			(size 0.254 0.381)
			(layers "F.Cu" "F.Mask" "F.Paste")
			(net "HSC_IMON")
		)
		(pad "23" smd rect
			(at 2.237486 -1.249934 270)
			(size 0.254 0.381)
			(layers "F.Cu" "F.Mask" "F.Paste")
			(net "HSC_CS_4")
		)
		(pad "24" smd rect
			(at 2.250186 -1.75006 270)
			(size 0.254 0.3556)
			(layers "F.Cu" "F.Mask" "F.Paste")
			(net "HSC_OCREF")
		)
		(pad "25" smd rect
			(at 1.75006 -2.250186 180)
			(size 0.254 0.3556)
			(layers "F.Cu" "F.Mask" "F.Paste")
			(net "P12V_AUX")
		)
		(pad "26" smd rect
			(at 1.249934 -2.237486 180)
			(size 0.254 0.381)
			(layers "F.Cu" "F.Mask" "F.Paste")
			(net "P12V_AUX")
		)
		(pad "27" smd rect
			(at 0.750062 -2.237486 180)
			(size 0.254 0.381)
			(layers "F.Cu" "F.Mask" "F.Paste")
			(net "P12V_AUX")
		)
		(pad "28" smd rect
			(at 0.249936 -2.237486 180)
			(size 0.254 0.381)
			(layers "F.Cu" "F.Mask" "F.Paste")
			(net "P12V_AUX")
		)
		(pad "29" smd rect
			(at -0.249936 -2.237486 180)
			(size 0.254 0.381)
			(layers "F.Cu" "F.Mask" "F.Paste")
			(net "P12V_AUX")
		)
		(pad "30" smd rect
			(at -0.750062 -2.237486 180)
			(size 0.254 0.381)
			(layers "F.Cu" "F.Mask" "F.Paste")
			(net "P12V_AUX")
		)
		(pad "31" smd rect
			(at -1.249934 -2.237486 180)
			(size 0.254 0.381)
			(layers "F.Cu" "F.Mask" "F.Paste")
			(net "P12V_AUX")
		)
		(pad "32" smd rect
			(at -1.75006 -2.250186 180)
			(size 0.254 0.3556)
			(layers "F.Cu" "F.Mask" "F.Paste")
			(net "P12V_AUX")
		)
		(pad "33" smd rect
			(at 0 0 180)
			(size 3.4036 3.4036)
			(layers "F.Cu" "F.Mask" "F.Paste")
			(net "P12V_PSU")
		)
		(zone
			(layer "F.Cu")
			(hatch none 0.5)
			(connect_pads
				(clearance 0)
			)
			(min_thickness 0.25)
			(keepout
				(tracks not_allowed)
				(vias allowed)
				(pads allowed)
				(copperpour not_allowed)
				(footprints allowed)
			)
			(placement
				(enabled no)
				(sheetname "")
			)
			(fill
				(thermal_gap 0.5)
				(thermal_bridge_width 0.5)
				(island_removal_mode 0)
			)
			(polygon
				(pts
					(xy 229.518972 -403.479) (xy 229.787958 -403.479) (xy 229.787958 -400.167602) (xy 233.293158 -400.167602)
					(xy 233.293158 -402.428202) (xy 233.536744 -402.428202) (xy 233.536744 -400.472402) (xy 233.562144 -400.472402)
					(xy 233.562144 -399.898616) (xy 232.988358 -399.898616) (xy 232.988358 -399.924016) (xy 230.092758 -399.924016)
					(xy 230.092758 -399.898616) (xy 229.518972 -399.898616) (xy 229.518972 -400.472402) (xy 229.544372 -400.472402)
					(xy 229.544372 -403.368002) (xy 229.518972 -403.368002)
				)
			)
		)
	)
)
